# S9S_MB_2U (Grand Teton) — schematic netlist excerpt (pin names and nets, part order shuffled) for the footprints in the layout excerpt that follows; sources: Cadence DE-HDL packaged netlist, KiCad conversion of 03242023_DA0F0TMBIJ0_F0T_Motherboard_J_brd_V01_OCP.brd

PR3829  Q_RES  7.15K 1% CHIP  pkg 0402LF  page 162 : A = P3V3_OCP_UV_2 ; B = P3V3_OCP_OV_2
C962  Q_CAP_DIFFBUS  DIFF BUS_0.22UF 6.3V 20% X6S  pkg C0201  page 173 : \1\ = P5E_CPU0_PE2_TX_C_DN<1> ; \2\ = P5E_CPU0_PE2_TX_DN<1>
C2015  Q_CAP  0.1UF 25V 10% X7R  pkg 0402  page 171 : A = P3V3_AUX ; B = GND

(kicad_pcb
	(version 20260206)
	(generator "pcbnew")
	(generator_version "10.0")
	(general
		(thickness 1.6)
		(legacy_teardrops no)
	)
	(paper "A4")
	(title_block
		(title "03242023_DA0F0TMBIJ0_F0T_Motherboard_J_brd_V01_OCP.brd")
		(comment 1 "Grand Teton / footprints 1358-1360 of 6105")
	)
	(layers
		(0 "F.Cu" signal "TOP")
		(4 "In1.Cu" signal "GND")
		(6 "In2.Cu" signal "IN1")
		(8 "In3.Cu" signal "GND1")
		(10 "In4.Cu" signal "IN2")
		(12 "In5.Cu" signal "GND2")
		(14 "In6.Cu" signal "IN3")
		(16 "In7.Cu" signal "GND3")
		(18 "In8.Cu" signal "VCC")
		(20 "In9.Cu" signal "VCC1")
		(22 "In10.Cu" signal "GND4")
		(24 "In11.Cu" signal "IN4")
		(26 "In12.Cu" signal "GND5")
		(28 "In13.Cu" signal "IN5")
		(30 "In14.Cu" signal "GND6")
		(32 "In15.Cu" signal "IN6")
		(34 "In16.Cu" signal "GND7")
		(2 "B.Cu" signal "BOTTOM")
		(9 "F.Adhes" user "F.Adhesive")
		(11 "B.Adhes" user "B.Adhesive")
		(13 "F.Paste" user "Package Geometry/Pastemask Top")
		(15 "B.Paste" user "Package Geometry/Pastemask Bottom")
		(5 "F.SilkS" user "Ref Des/Silkscreen Top")
		(7 "B.SilkS" user "Ref Des/Silkscreen Bottom")
		(1 "F.Mask" user "Board Geometry/Soldermask Top")
		(3 "B.Mask" user "Board Geometry/Soldermask Bottom")
		(17 "Dwgs.User" user "User.Drawings")
		(19 "Cmts.User" user "User.Comments")
		(21 "Eco1.User" user "User.Eco1")
		(23 "Eco2.User" user "User.Eco2")
		(25 "Edge.Cuts" user "Board Geometry/Outline")
		(27 "Margin" user)
		(31 "F.CrtYd" user "Package Geometry/Place Bound Top")
		(29 "B.CrtYd" user "Package Geometry/Place Bound Bottom")
		(35 "F.Fab" user "Ref Des/Assembly Top")
		(33 "B.Fab" user "Ref Des/Assembly Bottom")
	)
	(footprint ""
		(layer "F.Cu")
		(at 80.384396 -57.977532 180)
		(property "Reference" "PR3829"
			(at 0 0 180)
			(layer "F.SilkS")
			(hide yes)
			(effects
				(font
					(size 1.27 1.27)
				)
			)
		)
		(property "Value" ""
			(at 0 0 180)
			(layer "F.Fab")
			(effects
				(font
					(size 1.27 1.27)
				)
			)
		)
		(duplicate_pad_numbers_are_jumpers no)
		(fp_line
			(start 0.7874 0.4064)
			(end -0.7874 0.4064)
			(stroke
				(width 0.1524)
				(type default)
			)
			(layer "F.SilkS")
		)
		(fp_line
			(start 0.7874 -0.4064)
			(end 0.7874 0.4064)
			(stroke
				(width 0.1524)
				(type default)
			)
			(layer "F.SilkS")
		)
		(fp_line
			(start -0.7874 0.4064)
			(end -0.7874 -0.4064)
			(stroke
				(width 0.1524)
				(type default)
			)
			(layer "F.SilkS")
		)
		(fp_line
			(start -0.7874 -0.4064)
			(end 0.7874 -0.4064)
			(stroke
				(width 0.1524)
				(type default)
			)
			(layer "F.SilkS")
		)
		(fp_line
			(start 0.67945 0.3048)
			(end 0.120396 0.3048)
			(stroke
				(width 0.1)
				(type default)
			)
			(layer "F.Fab")
		)
		(fp_line
			(start 0.67945 -0.3048)
			(end 0.67945 0.3048)
			(stroke
				(width 0.1)
				(type default)
			)
			(layer "F.Fab")
		)
		(fp_line
			(start 0.12065 -0.2794)
			(end 0.12065 -0.3048)
			(stroke
				(width 0.1)
				(type default)
			)
			(layer "F.Fab")
		)
		(fp_line
			(start 0.12065 -0.3048)
			(end 0.67945 -0.3048)
			(stroke
				(width 0.1)
				(type default)
			)
			(layer "F.Fab")
		)
		(fp_line
			(start 0.120396 0.3048)
			(end 0.120396 0.2794)
			(stroke
				(width 0.1)
				(type default)
			)
			(layer "F.Fab")
		)
		(fp_line
			(start 0.120396 0.2794)
			(end -0.12065 0.2794)
			(stroke
				(width 0.1)
				(type default)
			)
			(layer "F.Fab")
		)
		(fp_line
			(start -0.12065 0.3048)
			(end -0.67945 0.3048)
			(stroke
				(width 0.1)
				(type default)
			)
			(layer "F.Fab")
		)
		(fp_line
			(start -0.12065 0.2794)
			(end -0.12065 0.3048)
			(stroke
				(width 0.1)
				(type default)
			)
			(layer "F.Fab")
		)
		(fp_line
			(start -0.12065 -0.2794)
			(end 0.12065 -0.2794)
			(stroke
				(width 0.1)
				(type default)
			)
			(layer "F.Fab")
		)
		(fp_line
			(start -0.12065 -0.305054)
			(end -0.12065 -0.2794)
			(stroke
				(width 0.1)
				(type default)
			)
			(layer "F.Fab")
		)
		(fp_line
			(start -0.67945 0.3048)
			(end -0.67945 -0.305054)
			(stroke
				(width 0.1)
				(type default)
			)
			(layer "F.Fab")
		)
		(fp_line
			(start -0.67945 -0.305054)
			(end -0.12065 -0.305054)
			(stroke
				(width 0.1)
				(type default)
			)
			(layer "F.Fab")
		)
		(pad "1" smd circle
			(at -0.40005 0 180)
			(size 0 0)
			(layers "F.Cu" "F.Mask" "F.Paste")
			(net "P3V3_OCP_UV_2")
		)
		(pad "2" smd circle
			(at 0.40005 0 180)
			(size 0 0)
			(layers "F.Cu" "F.Mask" "F.Paste")
			(net "P3V3_OCP_OV_2")
		)
	)
	(footprint ""
		(layer "F.Cu")
		(at 438.277 -96.357948 90)
		(property "Reference" "C2015"
			(at 0 0 90)
			(layer "F.SilkS")
			(hide yes)
			(effects
				(font
					(size 1.27 1.27)
				)
			)
		)
		(property "Value" ""
			(at 0 0 90)
			(layer "F.Fab")
			(effects
				(font
					(size 1.27 1.27)
				)
			)
		)
		(duplicate_pad_numbers_are_jumpers no)
		(fp_line
			(start 0.7874 -0.4064)
			(end 0.7874 0.4064)
			(stroke
				(width 0.1524)
				(type default)
			)
			(layer "F.SilkS")
		)
		(fp_line
			(start -0.7874 -0.4064)
			(end 0.7874 -0.4064)
			(stroke
				(width 0.1524)
				(type default)
			)
			(layer "F.SilkS")
		)
		(fp_line
			(start 0.7874 0.4064)
			(end -0.7874 0.4064)
			(stroke
				(width 0.1524)
				(type default)
			)
			(layer "F.SilkS")
		)
		(fp_line
			(start -0.7874 0.4064)
			(end -0.7874 -0.4064)
			(stroke
				(width 0.1524)
				(type default)
			)
			(layer "F.SilkS")
		)
		(fp_line
			(start -0.12065 -0.305054)
			(end -0.12065 -0.2794)
			(stroke
				(width 0.1)
				(type default)
			)
			(layer "F.Fab")
		)
		(fp_line
			(start -0.67945 -0.305054)
			(end -0.12065 -0.305054)
			(stroke
				(width 0.1)
				(type default)
			)
			(layer "F.Fab")
		)
		(fp_line
			(start 0.67945 -0.3048)
			(end 0.67945 0.3048)
			(stroke
				(width 0.1)
				(type default)
			)
			(layer "F.Fab")
		)
		(fp_line
			(start 0.12065 -0.3048)
			(end 0.67945 -0.3048)
			(stroke
				(width 0.1)
				(type default)
			)
			(layer "F.Fab")
		)
		(fp_line
			(start 0.12065 -0.2794)
			(end 0.12065 -0.3048)
			(stroke
				(width 0.1)
				(type default)
			)
			(layer "F.Fab")
		)
		(fp_line
			(start -0.12065 -0.2794)
			(end 0.12065 -0.2794)
			(stroke
				(width 0.1)
				(type default)
			)
			(layer "F.Fab")
		)
		(fp_line
			(start 0.120396 0.2794)
			(end -0.12065 0.2794)
			(stroke
				(width 0.1)
				(type default)
			)
			(layer "F.Fab")
		)
		(fp_line
			(start -0.12065 0.2794)
			(end -0.12065 0.3048)
			(stroke
				(width 0.1)
				(type default)
			)
			(layer "F.Fab")
		)
		(fp_line
			(start 0.67945 0.3048)
			(end 0.120396 0.3048)
			(stroke
				(width 0.1)
				(type default)
			)
			(layer "F.Fab")
		)
		(fp_line
			(start 0.120396 0.3048)
			(end 0.120396 0.2794)
			(stroke
				(width 0.1)
				(type default)
			)
			(layer "F.Fab")
		)
		(fp_line
			(start -0.12065 0.3048)
			(end -0.67945 0.3048)
			(stroke
				(width 0.1)
				(type default)
			)
			(layer "F.Fab")
		)
		(fp_line
			(start -0.67945 0.3048)
			(end -0.67945 -0.305054)
			(stroke
				(width 0.1)
				(type default)
			)
			(layer "F.Fab")
		)
		(pad "1" smd circle
			(at -0.40005 0 90)
			(size 0 0)
			(layers "F.Cu" "F.Mask" "F.Paste")
			(net "P3V3_AUX")
		)
		(pad "2" smd circle
			(at 0.40005 0 90)
			(size 0 0)
			(layers "F.Cu" "F.Mask" "F.Paste")
			(net "GND")
		)
	)
	(footprint ""
		(layer "F.Cu")
		(at 415.19729 -402.371052 -90)
		(property "Reference" "C962"
			(at 0 0 270)
			(layer "F.SilkS")
			(hide yes)
			(effects
				(font
					(size 1.27 1.27)
				)
			)
		)
		(property "Value" ""
			(at 0 0 270)
			(layer "F.Fab")
			(effects
				(font
					(size 1.27 1.27)
				)
			)
		)
		(duplicate_pad_numbers_are_jumpers no)
		(fp_line
			(start -0.299974 0.150114)
			(end -0.299974 -0.150114)
			(stroke
				(width 0.1)
				(type default)
			)
			(layer "F.Fab")
		)
		(fp_line
			(start 0.299974 0.150114)
			(end -0.299974 0.150114)
			(stroke
				(width 0.1)
				(type default)
			)
			(layer "F.Fab")
		)
		(fp_line
			(start -0.299974 -0.150114)
			(end 0.299974 -0.150114)
			(stroke
				(width 0.1)
				(type default)
			)
			(layer "F.Fab")
		)
		(fp_line
			(start 0.299974 -0.150114)
			(end 0.299974 0.150114)
			(stroke
				(width 0.1)
				(type default)
			)
			(layer "F.Fab")
		)
		(pad "1" smd rect
			(at -0.2667 0 270)
			(size 0.3048 0.381)
			(layers "F.Cu" "F.Mask" "F.Paste")
			(net "P5E_CPU0_PE2_TX_C_DN<1>")
		)
		(pad "2" smd rect
			(at 0.2667 0 270)
			(size 0.3048 0.381)
			(layers "F.Cu" "F.Mask" "F.Paste")
			(net "P5E_CPU0_PE2_TX_DN<1>")
		)
	)
)
